# T6G (Grand Teton) — schematic netlist excerpt (pin names and nets, part order shuffled) for the footprints in the layout excerpt that follows; sources: Cadence DE-HDL packaged netlist, KiCad conversion of 04192023_DAF0TMB3IC0_F0TG_MB_C_brd_V02_OCP.brd

PR358  Q_RES  8.87K 1% EMPTY  pkg 0402LF  page 198 : A = GND ; B = PVDDCR_SOC_P0_LSET1

Q57  MOSFET_NCH_1D3S  PSMNR58-30YLH IC  pkg SOT1023  page 188
  \1\  = P5V
  \2\  = P5V
  \3\  = P5V
  \4\  = VR_P5V_EN_D_R
  \5\  = P5V_AUX

(kicad_pcb
	(version 20260206)
	(generator "pcbnew")
	(generator_version "10.0")
	(general
		(thickness 1.6)
		(legacy_teardrops no)
	)
	(paper "A4")
	(title_block
		(title "04192023_DAF0TMB3IC0_F0TG_MB_C_brd_V02_OCP.brd")
		(comment 1 "Grand Teton / footprints 2567-2568 of 8354")
	)
	(layers
		(0 "F.Cu" signal "TOP")
		(4 "In1.Cu" signal "GND")
		(6 "In2.Cu" signal "IN1")
		(8 "In3.Cu" signal "GND1")
		(10 "In4.Cu" signal "IN2")
		(12 "In5.Cu" signal "GND2")
		(14 "In6.Cu" signal "IN3")
		(16 "In7.Cu" signal "GND3")
		(18 "In8.Cu" signal "VCC")
		(20 "In9.Cu" signal "VCC1")
		(22 "In10.Cu" signal "GND4")
		(24 "In11.Cu" signal "IN4")
		(26 "In12.Cu" signal "GND5")
		(28 "In13.Cu" signal "IN5")
		(30 "In14.Cu" signal "GND6")
		(32 "In15.Cu" signal "IN6")
		(34 "In16.Cu" signal "GND7")
		(2 "B.Cu" signal "BOTTOM")
		(9 "F.Adhes" user "F.Adhesive")
		(11 "B.Adhes" user "B.Adhesive")
		(13 "F.Paste" user "Package Geometry/Pastemask Top")
		(15 "B.Paste" user "Package Geometry/Pastemask Bottom")
		(5 "F.SilkS" user "Ref Des/Silkscreen Top")
		(7 "B.SilkS" user "Ref Des/Silkscreen Bottom")
		(1 "F.Mask" user "Board Geometry/Soldermask Top")
		(3 "B.Mask" user "Board Geometry/Soldermask Bottom")
		(17 "Dwgs.User" user "User.Drawings")
		(19 "Cmts.User" user "User.Comments")
		(21 "Eco1.User" user "User.Eco1")
		(23 "Eco2.User" user "User.Eco2")
		(25 "Edge.Cuts" user "Board Geometry/Outline")
		(27 "Margin" user)
		(31 "F.CrtYd" user "Package Geometry/Place Bound Top")
		(29 "B.CrtYd" user "Package Geometry/Place Bound Bottom")
		(35 "F.Fab" user "Ref Des/Assembly Top")
		(33 "B.Fab" user "Ref Des/Assembly Bottom")
	)
	(footprint ""
		(layer "F.Cu")
		(at 403.476714 -147.706588)
		(property "Reference" "Q57"
			(at -2.2225 -3.470402 0)
			(unlocked yes)
			(layer "F.SilkS")
			(effects
				(font
					(size 0.7874 0.5842)
					(thickness 0.1524)
				)
				(justify left)
			)
		)
		(property "Value" ""
			(at 0 0 0)
			(layer "F.Fab")
			(effects
				(font
					(size 1.27 1.27)
				)
			)
		)
		(duplicate_pad_numbers_are_jumpers no)
		(fp_line
			(start -2.350008 -2.649982)
			(end 2.350008 -2.649982)
			(stroke
				(width 0.1524)
				(type default)
			)
			(layer "F.SilkS")
		)
		(fp_line
			(start -2.350008 -2.4384)
			(end -2.350008 -2.649982)
			(stroke
				(width 0.1524)
				(type default)
			)
			(layer "F.SilkS")
		)
		(fp_line
			(start -2.350008 2.649982)
			(end -2.350008 2.413)
			(stroke
				(width 0.1524)
				(type default)
			)
			(layer "F.SilkS")
		)
		(fp_line
			(start 2.350008 -2.649982)
			(end 2.350008 -2.4892)
			(stroke
				(width 0.1524)
				(type default)
			)
			(layer "F.SilkS")
		)
		(fp_line
			(start 2.350008 2.4892)
			(end 2.350008 2.649982)
			(stroke
				(width 0.1524)
				(type default)
			)
			(layer "F.SilkS")
		)
		(fp_line
			(start 2.350008 2.649982)
			(end -2.350008 2.649982)
			(stroke
				(width 0.1524)
				(type default)
			)
			(layer "F.SilkS")
		)
		(fp_poly
			(pts
				(xy -5.142992 -3.626866) (xy -4.444238 -2.74828) (xy -5.537962 -2.930906)
			)
			(stroke
				(width 0)
				(type default)
			)
			(fill yes)
			(layer "F.SilkS")
		)
		(fp_line
			(start -2.350008 -2.649982)
			(end 2.350008 -2.649982)
			(stroke
				(width 0.1)
				(type default)
			)
			(layer "F.Fab")
		)
		(fp_line
			(start -2.350008 2.649982)
			(end -2.350008 -2.649982)
			(stroke
				(width 0.1)
				(type default)
			)
			(layer "F.Fab")
		)
		(fp_line
			(start 2.350008 -2.649982)
			(end 2.350008 2.649982)
			(stroke
				(width 0.1)
				(type default)
			)
			(layer "F.Fab")
		)
		(fp_line
			(start 2.350008 2.649982)
			(end -2.350008 2.649982)
			(stroke
				(width 0.1)
				(type default)
			)
			(layer "F.Fab")
		)
		(fp_poly
			(pts
				(xy -3.717544 -1.905) (xy -4.758944 -2.3241) (xy -4.758944 -1.524)
			)
			(stroke
				(width 0)
				(type default)
			)
			(fill yes)
			(layer "F.Fab")
		)
		(pad "1" smd rect
			(at -2.999994 -1.905 270)
			(size 0.7112 1.1684)
			(layers "F.Cu" "F.Mask" "F.Paste")
			(net "P5V")
		)
		(pad "2" smd rect
			(at -2.999994 -0.635 270)
			(size 0.7112 1.1684)
			(layers "F.Cu" "F.Mask" "F.Paste")
			(net "P5V")
		)
		(pad "3" smd rect
			(at -2.999994 0.635 270)
			(size 0.7112 1.1684)
			(layers "F.Cu" "F.Mask" "F.Paste")
			(net "P5V")
		)
		(pad "4" smd rect
			(at -2.999994 1.905 270)
			(size 0.7112 1.1684)
			(layers "F.Cu" "F.Mask" "F.Paste")
			(net "VR_P5V_EN_D_R")
		)
		(pad "5" smd circle
			(at 0.925068 0 270)
			(size 0 0)
			(layers "F.Cu" "F.Mask" "F.Paste")
			(net "P5V_AUX")
		)
		(zone
			(layer "F.Cu")
			(hatch none 0.5)
			(connect_pads
				(clearance 0)
			)
			(min_thickness 0.25)
			(keepout
				(tracks not_allowed)
				(vias allowed)
				(pads allowed)
				(copperpour not_allowed)
				(footprints allowed)
			)
			(placement
				(enabled no)
				(sheetname "")
			)
			(fill
				(thermal_gap 0.5)
				(thermal_bridge_width 0.5)
				(island_removal_mode 0)
			)
			(polygon
				(pts
					(xy 402.086064 -149.865588) (xy 402.028914 -149.865588) (xy 402.028914 -145.547588) (xy 402.091144 -145.547588)
					(xy 402.091144 -145.064988) (xy 401.127214 -145.064988) (xy 401.127214 -150.348188) (xy 402.086064 -150.348188)
				)
			)
		)
	)
	(footprint ""
		(layer "F.Cu")
		(at 399.128742 -171.959524)
		(property "Reference" "PR358"
			(at 0 0 0)
			(layer "F.SilkS")
			(hide yes)
			(effects
				(font
					(size 1.27 1.27)
				)
			)
		)
		(property "Value" ""
			(at 0 0 0)
			(layer "F.Fab")
			(effects
				(font
					(size 1.27 1.27)
				)
			)
		)
		(duplicate_pad_numbers_are_jumpers no)
		(fp_line
			(start -0.7874 -0.4064)
			(end 0.7874 -0.4064)
			(stroke
				(width 0.1524)
				(type default)
			)
			(layer "F.SilkS")
		)
		(fp_line
			(start -0.7874 0.4064)
			(end -0.7874 -0.4064)
			(stroke
				(width 0.1524)
				(type default)
			)
			(layer "F.SilkS")
		)
		(fp_line
			(start 0.7874 -0.4064)
			(end 0.7874 0.4064)
			(stroke
				(width 0.1524)
				(type default)
			)
			(layer "F.SilkS")
		)
		(fp_line
			(start 0.7874 0.4064)
			(end -0.7874 0.4064)
			(stroke
				(width 0.1524)
				(type default)
			)
			(layer "F.SilkS")
		)
		(fp_line
			(start -0.67945 -0.305054)
			(end -0.12065 -0.305054)
			(stroke
				(width 0.1)
				(type default)
			)
			(layer "F.Fab")
		)
		(fp_line
			(start -0.67945 0.3048)
			(end -0.67945 -0.305054)
			(stroke
				(width 0.1)
				(type default)
			)
			(layer "F.Fab")
		)
		(fp_line
			(start -0.12065 -0.305054)
			(end -0.12065 -0.2794)
			(stroke
				(width 0.1)
				(type default)
			)
			(layer "F.Fab")
		)
		(fp_line
			(start -0.12065 -0.2794)
			(end 0.12065 -0.2794)
			(stroke
				(width 0.1)
				(type default)
			)
			(layer "F.Fab")
		)
		(fp_line
			(start -0.12065 0.2794)
			(end -0.12065 0.3048)
			(stroke
				(width 0.1)
				(type default)
			)
			(layer "F.Fab")
		)
		(fp_line
			(start -0.12065 0.3048)
			(end -0.67945 0.3048)
			(stroke
				(width 0.1)
				(type default)
			)
			(layer "F.Fab")
		)
		(fp_line
			(start 0.120396 0.2794)
			(end -0.12065 0.2794)
			(stroke
				(width 0.1)
				(type default)
			)
			(layer "F.Fab")
		)
		(fp_line
			(start 0.120396 0.3048)
			(end 0.120396 0.2794)
			(stroke
				(width 0.1)
				(type default)
			)
			(layer "F.Fab")
		)
		(fp_line
			(start 0.12065 -0.3048)
			(end 0.67945 -0.3048)
			(stroke
				(width 0.1)
				(type default)
			)
			(layer "F.Fab")
		)
		(fp_line
			(start 0.12065 -0.2794)
			(end 0.12065 -0.3048)
			(stroke
				(width 0.1)
				(type default)
			)
			(layer "F.Fab")
		)
		(fp_line
			(start 0.67945 -0.3048)
			(end 0.67945 0.3048)
			(stroke
				(width 0.1)
				(type default)
			)
			(layer "F.Fab")
		)
		(fp_line
			(start 0.67945 0.3048)
			(end 0.120396 0.3048)
			(stroke
				(width 0.1)
				(type default)
			)
			(layer "F.Fab")
		)
		(pad "1" smd circle
			(at -0.40005 0)
			(size 0 0)
			(layers "F.Cu" "F.Mask" "F.Paste")
			(net "GND")
		)
		(pad "2" smd circle
			(at 0.40005 0)
			(size 0 0)
			(layers "F.Cu" "F.Mask" "F.Paste")
			(net "PVDDCR_SOC_P0_LSET1")
		)
	)
)
